(kicad_pcb
	(version 20260206)
	(generator "pcbnew")
	(generator_version "10.0")
	(general
		(thickness 1.6)
		(legacy_teardrops no)
	)
	(paper "A4")
	(title_block
		(title "01162023_DA0F0TEBIF0_F0T_Expander_BD_F_brd_V02_OCP.brd")
		(comment 1 "Grand Teton / footprint 6602 of 9728 (PEX1), pads 117-233 of 2397")
	)
	(layers
		(0 "F.Cu" signal "TOP")
		(4 "In1.Cu" signal "GND")
		(6 "In2.Cu" signal "VCC")
		(8 "In3.Cu" signal "VCC1")
		(10 "In4.Cu" signal "GND1")
		(12 "In5.Cu" signal "IN1")
		(14 "In6.Cu" signal "GND2")
		(16 "In7.Cu" signal "IN2")
		(18 "In8.Cu" signal "GND3")
		(20 "In9.Cu" signal "IN3")
		(22 "In10.Cu" signal "GND4")
		(24 "In11.Cu" signal "IN4")
		(26 "In12.Cu" signal "GND5")
		(28 "In13.Cu" signal "IN5")
		(30 "In14.Cu" signal "GND6")
		(32 "In15.Cu" signal "IN6")
		(34 "In16.Cu" signal "GND7")
		(2 "B.Cu" signal "BOTTOM")
		(9 "F.Adhes" user "F.Adhesive")
		(11 "B.Adhes" user "B.Adhesive")
		(13 "F.Paste" user "Package Geometry/Pastemask Top")
		(15 "B.Paste" user "Package Geometry/Pastemask Bottom")
		(5 "F.SilkS" user "Ref Des/Silkscreen Top")
		(7 "B.SilkS" user "Ref Des/Silkscreen Bottom")
		(1 "F.Mask" user "Board Geometry/Soldermask Top")
		(3 "B.Mask" user "Board Geometry/Soldermask Bottom")
		(17 "Dwgs.User" user "User.Drawings")
		(19 "Cmts.User" user "User.Comments")
		(21 "Eco1.User" user "User.Eco1")
		(23 "Eco2.User" user "User.Eco2")
		(25 "Edge.Cuts" user "Board Geometry/Outline")
		(27 "Margin" user)
		(31 "F.CrtYd" user "Package Geometry/Place Bound Top")
		(29 "B.CrtYd" user "Package Geometry/Place Bound Bottom")
		(35 "F.Fab" user "Ref Des/Assembly Top")
		(33 "B.Fab" user "Ref Des/Assembly Bottom")
	)
	(footprint ""
		(layer "F.Cu")
		(at 175.749966 -295.89984)
		(property "Reference" "PEX1"
			(at -3.353562 35.593274 0)
			(unlocked yes)
			(layer "F.SilkS")
			(effects
				(font
					(size 2.032 1.524)
					(thickness 0.1524)
				)
				(justify left)
			)
		)
		(property "Value" ""
			(at 0 0 0)
			(layer "F.Fab")
			(effects
				(font
					(size 1.27 1.27)
				)
			)
		)
		(duplicate_pad_numbers_are_jumpers no)
		(pad "AB21" smd circle
			(at -3.800094 -2.84988)
			(size 0.4572 0.4572)
			(layers "F.Cu" "F.Mask" "F.Paste")
			(net "P0V8_SERDES_VDDA_PEX1")
		)
		(pad "AB22" smd circle
			(at -2.84988 -2.84988)
			(size 0.4572 0.4572)
			(layers "F.Cu" "F.Mask" "F.Paste")
			(net "P0V8_SERDES_VDDA_PEX1")
		)
		(pad "AB23" smd circle
			(at -1.89992 -2.84988)
			(size 0.4572 0.4572)
			(layers "F.Cu" "F.Mask" "F.Paste")
			(net "P0V8_SERDES_VDDA_PEX1")
		)
		(pad "AB24" smd circle
			(at -0.94996 -2.84988)
			(size 0.4572 0.4572)
			(layers "F.Cu" "F.Mask" "F.Paste")
			(net "P0V8_SERDES_VDDA_PEX1")
		)
		(pad "AB25" smd circle
			(at 0 -2.84988)
			(size 0.4572 0.4572)
			(layers "F.Cu" "F.Mask" "F.Paste")
			(net "P0V8_SERDES_VDDA_PEX1")
		)
		(pad "AB26" smd circle
			(at 0.94996 -2.84988)
			(size 0.4572 0.4572)
			(layers "F.Cu" "F.Mask" "F.Paste")
			(net "P0V8_SERDES_VDDA_PEX1")
		)
		(pad "AB27" smd circle
			(at 1.89992 -2.84988)
			(size 0.4572 0.4572)
			(layers "F.Cu" "F.Mask" "F.Paste")
			(net "P0V8_SERDES_VDDA_PEX1")
		)
		(pad "AB28" smd circle
			(at 2.84988 -2.84988)
			(size 0.4572 0.4572)
			(layers "F.Cu" "F.Mask" "F.Paste")
			(net "P0V8_SERDES_VDDA_PEX1")
		)
		(pad "AB29" smd circle
			(at 3.800094 -2.84988)
			(size 0.4572 0.4572)
			(layers "F.Cu" "F.Mask" "F.Paste")
			(net "P0V8_SERDES_VDDA_PEX1")
		)
		(pad "AB30" smd circle
			(at 4.750054 -2.84988)
			(size 0.4572 0.4572)
			(layers "F.Cu" "F.Mask" "F.Paste")
			(net "P0V8_SERDES_VDDA_PEX1")
		)
		(pad "AB31" smd circle
			(at 5.700014 -2.84988)
			(size 0.4572 0.4572)
			(layers "F.Cu" "F.Mask" "F.Paste")
			(net "P0V8_SERDES_VDDA_PEX1")
		)
		(pad "AB32" smd circle
			(at 6.649974 -2.84988)
			(size 0.4572 0.4572)
			(layers "F.Cu" "F.Mask" "F.Paste")
			(net "P0V8_SERDES_VDDA_PEX1")
		)
		(pad "AB33" smd circle
			(at 7.599934 -2.84988)
			(size 0.4572 0.4572)
			(layers "F.Cu" "F.Mask" "F.Paste")
			(net "P0V8_SERDES_VDDA_PEX1")
		)
		(pad "AB34" smd circle
			(at 8.549894 -2.84988)
			(size 0.4572 0.4572)
			(layers "F.Cu" "F.Mask" "F.Paste")
			(net "GND")
		)
		(pad "AB35" smd circle
			(at 9.500108 -2.84988)
			(size 0.4572 0.4572)
			(layers "F.Cu" "F.Mask" "F.Paste")
			(net "Net_509")
		)
		(pad "AB36" smd circle
			(at 10.450068 -2.84988)
			(size 0.4572 0.4572)
			(layers "F.Cu" "F.Mask" "F.Paste")
			(net "GND")
		)
		(pad "AB37" smd circle
			(at 11.400028 -2.84988)
			(size 0.4572 0.4572)
			(layers "F.Cu" "F.Mask" "F.Paste")
			(net "GND")
		)
		(pad "AB38" smd circle
			(at 12.349988 -2.84988)
			(size 0.4572 0.4572)
			(layers "F.Cu" "F.Mask" "F.Paste")
			(net "GND")
		)
		(pad "AB39" smd circle
			(at 13.299948 -2.84988)
			(size 0.4572 0.4572)
			(layers "F.Cu" "F.Mask" "F.Paste")
			(net "GND")
		)
		(pad "AB40" smd circle
			(at 14.249908 -2.84988)
			(size 0.4572 0.4572)
			(layers "F.Cu" "F.Mask" "F.Paste")
			(net "GND")
		)
		(pad "AB41" smd circle
			(at 15.200122 -2.84988)
			(size 0.4572 0.4572)
			(layers "F.Cu" "F.Mask" "F.Paste")
			(net "Net_1392")
		)
		(pad "AB42" smd circle
			(at 16.150082 -2.84988)
			(size 0.4572 0.4572)
			(layers "F.Cu" "F.Mask" "F.Paste")
			(net "Net_1379")
		)
		(pad "AB43" smd circle
			(at 17.100042 -2.84988)
			(size 0.4572 0.4572)
			(layers "F.Cu" "F.Mask" "F.Paste")
			(net "GND")
		)
		(pad "AB44" smd circle
			(at 18.050002 -2.84988)
			(size 0.4572 0.4572)
			(layers "F.Cu" "F.Mask" "F.Paste")
			(net "GND")
		)
		(pad "AB45" smd circle
			(at 18.999962 -2.84988)
			(size 0.4572 0.4572)
			(layers "F.Cu" "F.Mask" "F.Paste")
			(net "GND")
		)
		(pad "AB46" smd circle
			(at 19.949922 -2.84988)
			(size 0.4572 0.4572)
			(layers "F.Cu" "F.Mask" "F.Paste")
			(net "GND")
		)
		(pad "AB47" smd circle
			(at 20.899882 -2.84988)
			(size 0.4572 0.4572)
			(layers "F.Cu" "F.Mask" "F.Paste")
			(net "GND")
		)
		(pad "AB48" smd circle
			(at 21.850096 -2.84988)
			(size 0.4572 0.4572)
			(layers "F.Cu" "F.Mask" "F.Paste")
			(net "Net_1584")
		)
		(pad "AB49" smd circle
			(at 22.800056 -2.84988)
			(size 0.4572 0.4572)
			(layers "F.Cu" "F.Mask" "F.Paste")
			(net "Net_1610")
		)
		(pad "AC1" smd circle
			(at -22.800056 -1.89992)
			(size 0.4572 0.4572)
			(layers "F.Cu" "F.Mask" "F.Paste")
			(net "CLK_100M_DB2000QL_PEX1_S1_R_DN")
		)
		(pad "AC2" smd circle
			(at -21.850096 -1.89992)
			(size 0.4572 0.4572)
			(layers "F.Cu" "F.Mask" "F.Paste")
			(net "CLK_100M_DB2000QL_PEX1_S1_R_DP")
		)
		(pad "AC3" smd circle
			(at -20.899882 -1.89992)
			(size 0.4572 0.4572)
			(layers "F.Cu" "F.Mask" "F.Paste")
			(net "GND")
		)
		(pad "AC4" smd circle
			(at -19.949922 -1.89992)
			(size 0.4572 0.4572)
			(layers "F.Cu" "F.Mask" "F.Paste")
			(net "GND")
		)
		(pad "AC5" smd circle
			(at -18.999962 -1.89992)
			(size 0.4572 0.4572)
			(layers "F.Cu" "F.Mask" "F.Paste")
			(net "GND")
		)
		(pad "AC6" smd circle
			(at -18.050002 -1.89992)
			(size 0.4572 0.4572)
			(layers "F.Cu" "F.Mask" "F.Paste")
			(net "GND")
		)
		(pad "AC7" smd circle
			(at -17.100042 -1.89992)
			(size 0.4572 0.4572)
			(layers "F.Cu" "F.Mask" "F.Paste")
			(net "Net_5308")
		)
		(pad "AC8" smd circle
			(at -16.150082 -1.89992)
			(size 0.4572 0.4572)
			(layers "F.Cu" "F.Mask" "F.Paste")
			(net "Net_5310")
		)
		(pad "AC9" smd circle
			(at -15.200122 -1.89992)
			(size 0.4572 0.4572)
			(layers "F.Cu" "F.Mask" "F.Paste")
			(net "GND")
		)
		(pad "AC10" smd circle
			(at -14.249908 -1.89992)
			(size 0.4572 0.4572)
			(layers "F.Cu" "F.Mask" "F.Paste")
			(net "P1V8_VDDA_PEX1")
		)
		(pad "AC11" smd circle
			(at -13.299948 -1.89992)
			(size 0.4572 0.4572)
			(layers "F.Cu" "F.Mask" "F.Paste")
			(net "GND")
		)
		(pad "AC12" smd circle
			(at -12.349988 -1.89992)
			(size 0.4572 0.4572)
			(layers "F.Cu" "F.Mask" "F.Paste")
			(net "GND")
		)
		(pad "AC13" smd circle
			(at -11.400028 -1.89992)
			(size 0.4572 0.4572)
			(layers "F.Cu" "F.Mask" "F.Paste")
			(net "SYSPLL_VDDA18_PEX1")
		)
		(pad "AC14" smd circle
			(at -10.450068 -1.89992)
			(size 0.4572 0.4572)
			(layers "F.Cu" "F.Mask" "F.Paste")
			(net "GND")
		)
		(pad "AC15" smd circle
			(at -9.500108 -1.89992)
			(size 0.4572 0.4572)
			(layers "F.Cu" "F.Mask" "F.Paste")
			(net "P0V8_PEX1")
		)
		(pad "AC16" smd circle
			(at -8.549894 -1.89992)
			(size 0.4572 0.4572)
			(layers "F.Cu" "F.Mask" "F.Paste")
			(net "GND")
		)
		(pad "AC17" smd circle
			(at -7.599934 -1.89992)
			(size 0.4572 0.4572)
			(layers "F.Cu" "F.Mask" "F.Paste")
			(net "P0V8_PEX1")
		)
		(pad "AC18" smd circle
			(at -6.649974 -1.89992)
			(size 0.4572 0.4572)
			(layers "F.Cu" "F.Mask" "F.Paste")
			(net "GND")
		)
		(pad "AC19" smd circle
			(at -5.700014 -1.89992)
			(size 0.4572 0.4572)
			(layers "F.Cu" "F.Mask" "F.Paste")
			(net "P0V8_PEX1")
		)
		(pad "AC20" smd circle
			(at -4.750054 -1.89992)
			(size 0.4572 0.4572)
			(layers "F.Cu" "F.Mask" "F.Paste")
			(net "GND")
		)
		(pad "AC21" smd circle
			(at -3.800094 -1.89992)
			(size 0.4572 0.4572)
			(layers "F.Cu" "F.Mask" "F.Paste")
			(net "P0V8_PEX1")
		)
		(pad "AC22" smd circle
			(at -2.84988 -1.89992)
			(size 0.4572 0.4572)
			(layers "F.Cu" "F.Mask" "F.Paste")
			(net "GND")
		)
		(pad "AC23" smd circle
			(at -1.89992 -1.89992)
			(size 0.4572 0.4572)
			(layers "F.Cu" "F.Mask" "F.Paste")
			(net "P0V8_PEX1")
		)
		(pad "AC24" smd circle
			(at -0.94996 -1.89992)
			(size 0.4572 0.4572)
			(layers "F.Cu" "F.Mask" "F.Paste")
			(net "GND")
		)
		(pad "AC25" smd circle
			(at 0 -1.89992)
			(size 0.4572 0.4572)
			(layers "F.Cu" "F.Mask" "F.Paste")
			(net "P0V8_PEX1")
		)
		(pad "AC26" smd circle
			(at 0.94996 -1.89992)
			(size 0.4572 0.4572)
			(layers "F.Cu" "F.Mask" "F.Paste")
			(net "GND")
		)
		(pad "AC27" smd circle
			(at 1.89992 -1.89992)
			(size 0.4572 0.4572)
			(layers "F.Cu" "F.Mask" "F.Paste")
			(net "P0V8_PEX1")
		)
		(pad "AC28" smd circle
			(at 2.84988 -1.89992)
			(size 0.4572 0.4572)
			(layers "F.Cu" "F.Mask" "F.Paste")
			(net "GND")
		)
		(pad "AC29" smd circle
			(at 3.800094 -1.89992)
			(size 0.4572 0.4572)
			(layers "F.Cu" "F.Mask" "F.Paste")
			(net "P0V8_PEX1")
		)
		(pad "AC30" smd circle
			(at 4.750054 -1.89992)
			(size 0.4572 0.4572)
			(layers "F.Cu" "F.Mask" "F.Paste")
			(net "GND")
		)
		(pad "AC31" smd circle
			(at 5.700014 -1.89992)
			(size 0.4572 0.4572)
			(layers "F.Cu" "F.Mask" "F.Paste")
			(net "P0V8_PEX1")
		)
		(pad "AC32" smd circle
			(at 6.649974 -1.89992)
			(size 0.4572 0.4572)
			(layers "F.Cu" "F.Mask" "F.Paste")
			(net "GND")
		)
		(pad "AC33" smd circle
			(at 7.599934 -1.89992)
			(size 0.4572 0.4572)
			(layers "F.Cu" "F.Mask" "F.Paste")
			(net "P0V8_PEX1")
		)
		(pad "AC34" smd circle
			(at 8.549894 -1.89992)
			(size 0.4572 0.4572)
			(layers "F.Cu" "F.Mask" "F.Paste")
			(net "GND")
		)
		(pad "AC35" smd circle
			(at 9.500108 -1.89992)
			(size 0.4572 0.4572)
			(layers "F.Cu" "F.Mask" "F.Paste")
			(net "GND")
		)
		(pad "AC36" smd circle
			(at 10.450068 -1.89992)
			(size 0.4572 0.4572)
			(layers "F.Cu" "F.Mask" "F.Paste")
			(net "P1V25_PEX1")
		)
		(pad "AC37" smd circle
			(at 11.400028 -1.89992)
			(size 0.4572 0.4572)
			(layers "F.Cu" "F.Mask" "F.Paste")
			(net "GND")
		)
		(pad "AC38" smd circle
			(at 12.349988 -1.89992)
			(size 0.4572 0.4572)
			(layers "F.Cu" "F.Mask" "F.Paste")
			(net "P1V25_SERDES_VDDPLL_PEX1")
		)
		(pad "AC39" smd circle
			(at 13.299948 -1.89992)
			(size 0.4572 0.4572)
			(layers "F.Cu" "F.Mask" "F.Paste")
			(net "GND")
		)
		(pad "AC40" smd circle
			(at 14.249908 -1.89992)
			(size 0.4572 0.4572)
			(layers "F.Cu" "F.Mask" "F.Paste")
			(net "GND")
		)
		(pad "AC41" smd circle
			(at 15.200122 -1.89992)
			(size 0.4572 0.4572)
			(layers "F.Cu" "F.Mask" "F.Paste")
			(net "GND")
		)
		(pad "AC42" smd circle
			(at 16.150082 -1.89992)
			(size 0.4572 0.4572)
			(layers "F.Cu" "F.Mask" "F.Paste")
			(net "GND")
		)
		(pad "AC43" smd circle
			(at 17.100042 -1.89992)
			(size 0.4572 0.4572)
			(layers "F.Cu" "F.Mask" "F.Paste")
			(net "Net_1358")
		)
		(pad "AC44" smd circle
			(at 18.050002 -1.89992)
			(size 0.4572 0.4572)
			(layers "F.Cu" "F.Mask" "F.Paste")
			(net "Net_1417")
		)
		(pad "AC45" smd circle
			(at 18.999962 -1.89992)
			(size 0.4572 0.4572)
			(layers "F.Cu" "F.Mask" "F.Paste")
			(net "GND")
		)
		(pad "AC46" smd circle
			(at 19.949922 -1.89992)
			(size 0.4572 0.4572)
			(layers "F.Cu" "F.Mask" "F.Paste")
			(net "Net_1567")
		)
		(pad "AC47" smd circle
			(at 20.899882 -1.89992)
			(size 0.4572 0.4572)
			(layers "F.Cu" "F.Mask" "F.Paste")
			(net "Net_1579")
		)
		(pad "AC48" smd circle
			(at 21.850096 -1.89992)
			(size 0.4572 0.4572)
			(layers "F.Cu" "F.Mask" "F.Paste")
			(net "GND")
		)
		(pad "AC49" smd circle
			(at 22.800056 -1.89992)
			(size 0.4572 0.4572)
			(layers "F.Cu" "F.Mask" "F.Paste")
			(net "GND")
		)
		(pad "AD1" smd circle
			(at -22.800056 -0.94996)
			(size 0.4572 0.4572)
			(layers "F.Cu" "F.Mask" "F.Paste")
			(net "GND")
		)
		(pad "AD2" smd circle
			(at -21.850096 -0.94996)
			(size 0.4572 0.4572)
			(layers "F.Cu" "F.Mask" "F.Paste")
			(net "GND")
		)
		(pad "AD3" smd circle
			(at -20.899882 -0.94996)
			(size 0.4572 0.4572)
			(layers "F.Cu" "F.Mask" "F.Paste")
			(net "GND")
		)
		(pad "AD4" smd circle
			(at -19.949922 -0.94996)
			(size 0.4572 0.4572)
			(layers "F.Cu" "F.Mask" "F.Paste")
			(net "Net_386")
		)
		(pad "AD5" smd circle
			(at -18.999962 -0.94996)
			(size 0.4572 0.4572)
			(layers "F.Cu" "F.Mask" "F.Paste")
			(net "Net_385")
		)
		(pad "AD6" smd circle
			(at -18.050002 -0.94996)
			(size 0.4572 0.4572)
			(layers "F.Cu" "F.Mask" "F.Paste")
			(net "GND")
		)
		(pad "AD7" smd circle
			(at -17.100042 -0.94996)
			(size 0.4572 0.4572)
			(layers "F.Cu" "F.Mask" "F.Paste")
			(net "Net_5307")
		)
		(pad "AD8" smd circle
			(at -16.150082 -0.94996)
			(size 0.4572 0.4572)
			(layers "F.Cu" "F.Mask" "F.Paste")
			(net "Net_5309")
		)
		(pad "AD9" smd circle
			(at -15.200122 -0.94996)
			(size 0.4572 0.4572)
			(layers "F.Cu" "F.Mask" "F.Paste")
			(net "GND")
		)
		(pad "AD10" smd circle
			(at -14.249908 -0.94996)
			(size 0.4572 0.4572)
			(layers "F.Cu" "F.Mask" "F.Paste")
			(net "GND")
		)
		(pad "AD11" smd circle
			(at -13.299948 -0.94996)
			(size 0.4572 0.4572)
			(layers "F.Cu" "F.Mask" "F.Paste")
			(net "GND")
		)
		(pad "AD12" smd circle
			(at -12.349988 -0.94996)
			(size 0.4572 0.4572)
			(layers "F.Cu" "F.Mask" "F.Paste")
			(net "PCEPLL2_VDDA18_PEX1")
		)
		(pad "AD13" smd circle
			(at -11.400028 -0.94996)
			(size 0.4572 0.4572)
			(layers "F.Cu" "F.Mask" "F.Paste")
			(net "GND")
		)
		(pad "AD14" smd circle
			(at -10.450068 -0.94996)
			(size 0.4572 0.4572)
			(layers "F.Cu" "F.Mask" "F.Paste")
			(net "P0V8_PEX1")
		)
		(pad "AD15" smd circle
			(at -9.500108 -0.94996)
			(size 0.4572 0.4572)
			(layers "F.Cu" "F.Mask" "F.Paste")
			(net "GND")
		)
		(pad "AD16" smd circle
			(at -8.549894 -0.94996)
			(size 0.4572 0.4572)
			(layers "F.Cu" "F.Mask" "F.Paste")
			(net "P0V8_PEX1")
		)
		(pad "AD17" smd circle
			(at -7.599934 -0.94996)
			(size 0.4572 0.4572)
			(layers "F.Cu" "F.Mask" "F.Paste")
			(net "GND")
		)
		(pad "AD18" smd circle
			(at -6.649974 -0.94996)
			(size 0.4572 0.4572)
			(layers "F.Cu" "F.Mask" "F.Paste")
			(net "P0V8_PEX1")
		)
		(pad "AD19" smd circle
			(at -5.700014 -0.94996)
			(size 0.4572 0.4572)
			(layers "F.Cu" "F.Mask" "F.Paste")
			(net "GND")
		)
		(pad "AD20" smd circle
			(at -4.750054 -0.94996)
			(size 0.4572 0.4572)
			(layers "F.Cu" "F.Mask" "F.Paste")
			(net "P0V8_PEX1")
		)
		(pad "AD21" smd circle
			(at -3.800094 -0.94996)
			(size 0.4572 0.4572)
			(layers "F.Cu" "F.Mask" "F.Paste")
			(net "GND")
		)
		(pad "AD22" smd circle
			(at -2.84988 -0.94996)
			(size 0.4572 0.4572)
			(layers "F.Cu" "F.Mask" "F.Paste")
			(net "P0V8_PEX1")
		)
		(pad "AD23" smd circle
			(at -1.89992 -0.94996)
			(size 0.4572 0.4572)
			(layers "F.Cu" "F.Mask" "F.Paste")
			(net "GND")
		)
		(pad "AD24" smd circle
			(at -0.94996 -0.94996)
			(size 0.4572 0.4572)
			(layers "F.Cu" "F.Mask" "F.Paste")
			(net "P0V8_PEX1")
		)
		(pad "AD25" smd circle
			(at 0 -0.94996)
			(size 0.4572 0.4572)
			(layers "F.Cu" "F.Mask" "F.Paste")
			(net "GND")
		)
		(pad "AD26" smd circle
			(at 0.94996 -0.94996)
			(size 0.4572 0.4572)
			(layers "F.Cu" "F.Mask" "F.Paste")
			(net "P0V8_PEX1")
		)
		(pad "AD27" smd circle
			(at 1.89992 -0.94996)
			(size 0.4572 0.4572)
			(layers "F.Cu" "F.Mask" "F.Paste")
			(net "GND")
		)
		(pad "AD28" smd circle
			(at 2.84988 -0.94996)
			(size 0.4572 0.4572)
			(layers "F.Cu" "F.Mask" "F.Paste")
			(net "P0V8_PEX1")
		)
		(pad "AD29" smd circle
			(at 3.800094 -0.94996)
			(size 0.4572 0.4572)
			(layers "F.Cu" "F.Mask" "F.Paste")
			(net "GND")
		)
		(pad "AD30" smd circle
			(at 4.750054 -0.94996)
			(size 0.4572 0.4572)
			(layers "F.Cu" "F.Mask" "F.Paste")
			(net "P0V8_PEX1")
		)
		(pad "AD31" smd circle
			(at 5.700014 -0.94996)
			(size 0.4572 0.4572)
			(layers "F.Cu" "F.Mask" "F.Paste")
			(net "GND")
		)
		(pad "AD32" smd circle
			(at 6.649974 -0.94996)
			(size 0.4572 0.4572)
			(layers "F.Cu" "F.Mask" "F.Paste")
			(net "P0V8_SERDES_VDDA_PEX1")
		)
		(pad "AD33" smd circle
			(at 7.599934 -0.94996)
			(size 0.4572 0.4572)
			(layers "F.Cu" "F.Mask" "F.Paste")
			(net "P0V8_SERDES_VDDA_PEX1")
		)
		(pad "AD34" smd circle
			(at 8.549894 -0.94996)
			(size 0.4572 0.4572)
			(layers "F.Cu" "F.Mask" "F.Paste")
			(net "P0V8_SERDES_VDDA_PEX1")
		)
		(pad "AD35" smd circle
			(at 9.500108 -0.94996)
			(size 0.4572 0.4572)
			(layers "F.Cu" "F.Mask" "F.Paste")
			(net "GND")
		)
		(pad "AD36" smd circle
			(at 10.450068 -0.94996)
			(size 0.4572 0.4572)
			(layers "F.Cu" "F.Mask" "F.Paste")
			(net "P1V25_PEX1")
		)
		(pad "AD37" smd circle
			(at 11.400028 -0.94996)
			(size 0.4572 0.4572)
			(layers "F.Cu" "F.Mask" "F.Paste")
			(net "GND")
		)
		(pad "AD38" smd circle
			(at 12.349988 -0.94996)
			(size 0.4572 0.4572)
			(layers "F.Cu" "F.Mask" "F.Paste")
			(net "P1V25_SERDES_VDDPLL_PEX1")
		)
		(pad "AD39" smd circle
			(at 13.299948 -0.94996)
			(size 0.4572 0.4572)
			(layers "F.Cu" "F.Mask" "F.Paste")
			(net "GND")
		)
	)
)
